# S9S_MB_2U (Grand Teton) — schematic netlist excerpt (pin names and nets, part order shuffled) for the footprints in the layout excerpt that follows; sources: Cadence DE-HDL packaged netlist, KiCad conversion of 03242023_DA0F0TMBIJ0_F0T_Motherboard_J_brd_V01_OCP.brd

C1912  Q_CAP  0.01UF 50V 10% X7R  pkg C0402  page 217 : A = VCC_PLD_CORE ; B = GND
PR1776  Q_RES  0 5% CHIP  pkg 0402LF  page 275 : A = PVCCINFAON_CPU0_VOS1 ; B = PVCCINFAON_CPU0

(kicad_pcb
	(version 20260206)
	(generator "pcbnew")
	(generator_version "10.0")
	(general
		(thickness 1.6)
		(legacy_teardrops no)
	)
	(paper "A4")
	(title_block
		(title "03242023_DA0F0TMBIJ0_F0T_Motherboard_J_brd_V01_OCP.brd")
		(comment 1 "Grand Teton / footprints 4958-4959 of 6105")
	)
	(layers
		(0 "F.Cu" signal "TOP")
		(4 "In1.Cu" signal "GND")
		(6 "In2.Cu" signal "IN1")
		(8 "In3.Cu" signal "GND1")
		(10 "In4.Cu" signal "IN2")
		(12 "In5.Cu" signal "GND2")
		(14 "In6.Cu" signal "IN3")
		(16 "In7.Cu" signal "GND3")
		(18 "In8.Cu" signal "VCC")
		(20 "In9.Cu" signal "VCC1")
		(22 "In10.Cu" signal "GND4")
		(24 "In11.Cu" signal "IN4")
		(26 "In12.Cu" signal "GND5")
		(28 "In13.Cu" signal "IN5")
		(30 "In14.Cu" signal "GND6")
		(32 "In15.Cu" signal "IN6")
		(34 "In16.Cu" signal "GND7")
		(2 "B.Cu" signal "BOTTOM")
		(9 "F.Adhes" user "F.Adhesive")
		(11 "B.Adhes" user "B.Adhesive")
		(13 "F.Paste" user "Package Geometry/Pastemask Top")
		(15 "B.Paste" user "Package Geometry/Pastemask Bottom")
		(5 "F.SilkS" user "Ref Des/Silkscreen Top")
		(7 "B.SilkS" user "Ref Des/Silkscreen Bottom")
		(1 "F.Mask" user "Board Geometry/Soldermask Top")
		(3 "B.Mask" user "Board Geometry/Soldermask Bottom")
		(17 "Dwgs.User" user "User.Drawings")
		(19 "Cmts.User" user "User.Comments")
		(21 "Eco1.User" user "User.Eco1")
		(23 "Eco2.User" user "User.Eco2")
		(25 "Edge.Cuts" user "Board Geometry/Outline")
		(27 "Margin" user)
		(31 "F.CrtYd" user "Package Geometry/Place Bound Top")
		(29 "B.CrtYd" user "Package Geometry/Place Bound Bottom")
		(35 "F.Fab" user "Ref Des/Assembly Top")
		(33 "B.Fab" user "Ref Des/Assembly Bottom")
	)
	(footprint ""
		(layer "B.Cu")
		(at 180.155596 -112.97539 180)
		(property "Reference" "C1912"
			(at 0 0 0)
			(layer "B.SilkS")
			(hide yes)
			(effects
				(font
					(size 1.27 1.27)
				)
				(justify mirror)
			)
		)
		(property "Value" ""
			(at 0 0 0)
			(layer "B.Fab")
			(effects
				(font
					(size 1.27 1.27)
				)
				(justify mirror)
			)
		)
		(duplicate_pad_numbers_are_jumpers no)
		(fp_line
			(start 0.69215 0.2921)
			(end 0.69215 -0.2921)
			(stroke
				(width 0.1524)
				(type default)
			)
			(layer "B.SilkS")
		)
		(fp_line
			(start 0.69215 -0.2921)
			(end -0.69215 -0.2921)
			(stroke
				(width 0.1524)
				(type default)
			)
			(layer "B.SilkS")
		)
		(fp_line
			(start -0.69215 0.2921)
			(end 0.69215 0.2921)
			(stroke
				(width 0.1524)
				(type default)
			)
			(layer "B.SilkS")
		)
		(fp_line
			(start -0.69215 -0.2921)
			(end -0.69215 0.2921)
			(stroke
				(width 0.1524)
				(type default)
			)
			(layer "B.SilkS")
		)
		(fp_line
			(start 0.51435 0.2794)
			(end 0.51435 -0.2794)
			(stroke
				(width 0.1)
				(type default)
			)
			(layer "B.Fab")
		)
		(fp_line
			(start 0.51435 -0.2794)
			(end -0.51435 -0.2794)
			(stroke
				(width 0.1)
				(type default)
			)
			(layer "B.Fab")
		)
		(fp_line
			(start -0.51435 0.2794)
			(end 0.51435 0.2794)
			(stroke
				(width 0.1)
				(type default)
			)
			(layer "B.Fab")
		)
		(fp_line
			(start -0.51435 -0.2794)
			(end -0.51435 0.2794)
			(stroke
				(width 0.1)
				(type default)
			)
			(layer "B.Fab")
		)
		(pad "1" smd circle
			(at 0.40005 0)
			(size 0 0)
			(layers "B.Cu" "B.Mask" "B.Paste")
			(net "VCC_PLD_CORE")
		)
		(pad "2" smd circle
			(at -0.40005 0)
			(size 0 0)
			(layers "B.Cu" "B.Mask" "B.Paste")
			(net "GND")
		)
		(zone
			(layer "B.Cu")
			(hatch none 0.5)
			(connect_pads
				(clearance 0)
			)
			(min_thickness 0.25)
			(keepout
				(tracks not_allowed)
				(vias allowed)
				(pads allowed)
				(copperpour not_allowed)
				(footprints allowed)
			)
			(placement
				(enabled no)
				(sheetname "")
			)
			(fill
				(thermal_gap 0.5)
				(thermal_bridge_width 0.5)
				(island_removal_mode 0)
			)
			(polygon
				(pts
					(xy 179.965096 -113.06302) (xy 180.056536 -113.121186) (xy 180.255926 -113.121186) (xy 180.346096 -113.06302)
					(xy 180.346096 -112.88776) (xy 180.255926 -112.82934) (xy 180.056536 -112.82934) (xy 179.965096 -112.887506)
				)
			)
		)
	)
	(footprint ""
		(layer "B.Cu")
		(at 418.540692 -174.686468 180)
		(property "Reference" "PR1776"
			(at 0 0 0)
			(layer "B.SilkS")
			(hide yes)
			(effects
				(font
					(size 1.27 1.27)
				)
				(justify mirror)
			)
		)
		(property "Value" ""
			(at 0 0 0)
			(layer "B.Fab")
			(effects
				(font
					(size 1.27 1.27)
				)
				(justify mirror)
			)
		)
		(duplicate_pad_numbers_are_jumpers no)
		(fp_line
			(start 0.7874 0.4064)
			(end 0.7874 -0.4064)
			(stroke
				(width 0.1524)
				(type default)
			)
			(layer "B.SilkS")
		)
		(fp_line
			(start 0.7874 -0.4064)
			(end -0.7874 -0.4064)
			(stroke
				(width 0.1524)
				(type default)
			)
			(layer "B.SilkS")
		)
		(fp_line
			(start -0.7874 0.4064)
			(end 0.7874 0.4064)
			(stroke
				(width 0.1524)
				(type default)
			)
			(layer "B.SilkS")
		)
		(fp_line
			(start -0.7874 -0.4064)
			(end -0.7874 0.4064)
			(stroke
				(width 0.1524)
				(type default)
			)
			(layer "B.SilkS")
		)
		(fp_line
			(start 0.67945 0.3048)
			(end 0.67945 -0.305054)
			(stroke
				(width 0.1)
				(type default)
			)
			(layer "B.Fab")
		)
		(fp_line
			(start 0.67945 -0.305054)
			(end 0.12065 -0.305054)
			(stroke
				(width 0.1)
				(type default)
			)
			(layer "B.Fab")
		)
		(fp_line
			(start 0.12065 0.3048)
			(end 0.67945 0.3048)
			(stroke
				(width 0.1)
				(type default)
			)
			(layer "B.Fab")
		)
		(fp_line
			(start 0.12065 0.2794)
			(end 0.12065 0.3048)
			(stroke
				(width 0.1)
				(type default)
			)
			(layer "B.Fab")
		)
		(fp_line
			(start 0.12065 -0.2794)
			(end -0.12065 -0.2794)
			(stroke
				(width 0.1)
				(type default)
			)
			(layer "B.Fab")
		)
		(fp_line
			(start 0.12065 -0.305054)
			(end 0.12065 -0.2794)
			(stroke
				(width 0.1)
				(type default)
			)
			(layer "B.Fab")
		)
		(fp_line
			(start -0.120396 0.3048)
			(end -0.120396 0.2794)
			(stroke
				(width 0.1)
				(type default)
			)
			(layer "B.Fab")
		)
		(fp_line
			(start -0.120396 0.2794)
			(end 0.12065 0.2794)
			(stroke
				(width 0.1)
				(type default)
			)
			(layer "B.Fab")
		)
		(fp_line
			(start -0.12065 -0.2794)
			(end -0.12065 -0.3048)
			(stroke
				(width 0.1)
				(type default)
			)
			(layer "B.Fab")
		)
		(fp_line
			(start -0.12065 -0.3048)
			(end -0.67945 -0.3048)
			(stroke
				(width 0.1)
				(type default)
			)
			(layer "B.Fab")
		)
		(fp_line
			(start -0.67945 0.3048)
			(end -0.120396 0.3048)
			(stroke
				(width 0.1)
				(type default)
			)
			(layer "B.Fab")
		)
		(fp_line
			(start -0.67945 -0.3048)
			(end -0.67945 0.3048)
			(stroke
				(width 0.1)
				(type default)
			)
			(layer "B.Fab")
		)
		(pad "1" smd circle
			(at 0.40005 0)
			(size 0 0)
			(layers "B.Cu" "B.Mask" "B.Paste")
			(net "PVCCINFAON_CPU0_VOS1")
		)
		(pad "2" smd circle
			(at -0.40005 0)
			(size 0 0)
			(layers "B.Cu" "B.Mask" "B.Paste")
			(net "PVCCINFAON_CPU0")
		)
	)
)
